# T6G (Grand Teton) — schematic netlist excerpt (pin names and nets, part order shuffled) for the footprints in the layout excerpt that follows; sources: Cadence DE-HDL packaged netlist, KiCad conversion of 04192023_DAF0TMB3IC0_F0TG_MB_C_brd_V02_OCP.brd

R8006  Q_RES  33 5% CHIP  pkg 0402LF  page 77 : A = SPI_CPU0_D2 ; B = SPI_CPU0_R1_D2
R6191  Q_RES  0 5% CHIP  pkg 0201LF  page 180 : A = USB2_CPU0_P0_DN ; B = USB2_CPU0_P0_R1_DN
PC2236  Q_CAP  0.01UF 50V 10% EMPTY  pkg C0402  page 152 : A = P12V_SCM_R ; B = P12V_SCM_GATE

(kicad_pcb
	(version 20260206)
	(generator "pcbnew")
	(generator_version "10.0")
	(general
		(thickness 1.6)
		(legacy_teardrops no)
	)
	(paper "A4")
	(title_block
		(title "04192023_DAF0TMB3IC0_F0TG_MB_C_brd_V02_OCP.brd")
		(comment 1 "Grand Teton / footprints 1274-1276 of 8354")
	)
	(layers
		(0 "F.Cu" signal "TOP")
		(4 "In1.Cu" signal "GND")
		(6 "In2.Cu" signal "IN1")
		(8 "In3.Cu" signal "GND1")
		(10 "In4.Cu" signal "IN2")
		(12 "In5.Cu" signal "GND2")
		(14 "In6.Cu" signal "IN3")
		(16 "In7.Cu" signal "GND3")
		(18 "In8.Cu" signal "VCC")
		(20 "In9.Cu" signal "VCC1")
		(22 "In10.Cu" signal "GND4")
		(24 "In11.Cu" signal "IN4")
		(26 "In12.Cu" signal "GND5")
		(28 "In13.Cu" signal "IN5")
		(30 "In14.Cu" signal "GND6")
		(32 "In15.Cu" signal "IN6")
		(34 "In16.Cu" signal "GND7")
		(2 "B.Cu" signal "BOTTOM")
		(9 "F.Adhes" user "F.Adhesive")
		(11 "B.Adhes" user "B.Adhesive")
		(13 "F.Paste" user "Package Geometry/Pastemask Top")
		(15 "B.Paste" user "Package Geometry/Pastemask Bottom")
		(5 "F.SilkS" user "Ref Des/Silkscreen Top")
		(7 "B.SilkS" user "Ref Des/Silkscreen Bottom")
		(1 "F.Mask" user "Board Geometry/Soldermask Top")
		(3 "B.Mask" user "Board Geometry/Soldermask Bottom")
		(17 "Dwgs.User" user "User.Drawings")
		(19 "Cmts.User" user "User.Comments")
		(21 "Eco1.User" user "User.Eco1")
		(23 "Eco2.User" user "User.Eco2")
		(25 "Edge.Cuts" user "Board Geometry/Outline")
		(27 "Margin" user)
		(31 "F.CrtYd" user "Package Geometry/Place Bound Top")
		(29 "B.CrtYd" user "Package Geometry/Place Bound Bottom")
		(35 "F.Fab" user "Ref Des/Assembly Top")
		(33 "B.Fab" user "Ref Des/Assembly Bottom")
	)
	(footprint ""
		(layer "F.Cu")
		(at 191.295782 -29.283152 180)
		(property "Reference" "PC2236"
			(at 0 0 180)
			(layer "F.SilkS")
			(hide yes)
			(effects
				(font
					(size 1.27 1.27)
				)
			)
		)
		(property "Value" ""
			(at 0 0 180)
			(layer "F.Fab")
			(effects
				(font
					(size 1.27 1.27)
				)
			)
		)
		(duplicate_pad_numbers_are_jumpers no)
		(fp_line
			(start 0.7874 0.4064)
			(end -0.7874 0.4064)
			(stroke
				(width 0.1524)
				(type default)
			)
			(layer "F.SilkS")
		)
		(fp_line
			(start 0.7874 -0.4064)
			(end 0.7874 0.4064)
			(stroke
				(width 0.1524)
				(type default)
			)
			(layer "F.SilkS")
		)
		(fp_line
			(start -0.7874 0.4064)
			(end -0.7874 -0.4064)
			(stroke
				(width 0.1524)
				(type default)
			)
			(layer "F.SilkS")
		)
		(fp_line
			(start -0.7874 -0.4064)
			(end 0.7874 -0.4064)
			(stroke
				(width 0.1524)
				(type default)
			)
			(layer "F.SilkS")
		)
		(fp_line
			(start 0.67945 0.3048)
			(end 0.120396 0.3048)
			(stroke
				(width 0.1)
				(type default)
			)
			(layer "F.Fab")
		)
		(fp_line
			(start 0.67945 -0.3048)
			(end 0.67945 0.3048)
			(stroke
				(width 0.1)
				(type default)
			)
			(layer "F.Fab")
		)
		(fp_line
			(start 0.12065 -0.2794)
			(end 0.12065 -0.3048)
			(stroke
				(width 0.1)
				(type default)
			)
			(layer "F.Fab")
		)
		(fp_line
			(start 0.12065 -0.3048)
			(end 0.67945 -0.3048)
			(stroke
				(width 0.1)
				(type default)
			)
			(layer "F.Fab")
		)
		(fp_line
			(start 0.120396 0.3048)
			(end 0.120396 0.2794)
			(stroke
				(width 0.1)
				(type default)
			)
			(layer "F.Fab")
		)
		(fp_line
			(start 0.120396 0.2794)
			(end -0.12065 0.2794)
			(stroke
				(width 0.1)
				(type default)
			)
			(layer "F.Fab")
		)
		(fp_line
			(start -0.12065 0.3048)
			(end -0.67945 0.3048)
			(stroke
				(width 0.1)
				(type default)
			)
			(layer "F.Fab")
		)
		(fp_line
			(start -0.12065 0.2794)
			(end -0.12065 0.3048)
			(stroke
				(width 0.1)
				(type default)
			)
			(layer "F.Fab")
		)
		(fp_line
			(start -0.12065 -0.2794)
			(end 0.12065 -0.2794)
			(stroke
				(width 0.1)
				(type default)
			)
			(layer "F.Fab")
		)
		(fp_line
			(start -0.12065 -0.305054)
			(end -0.12065 -0.2794)
			(stroke
				(width 0.1)
				(type default)
			)
			(layer "F.Fab")
		)
		(fp_line
			(start -0.67945 0.3048)
			(end -0.67945 -0.305054)
			(stroke
				(width 0.1)
				(type default)
			)
			(layer "F.Fab")
		)
		(fp_line
			(start -0.67945 -0.305054)
			(end -0.12065 -0.305054)
			(stroke
				(width 0.1)
				(type default)
			)
			(layer "F.Fab")
		)
		(pad "1" smd circle
			(at -0.40005 0 180)
			(size 0 0)
			(layers "F.Cu" "F.Mask" "F.Paste")
			(net "P12V_SCM_R")
		)
		(pad "2" smd circle
			(at 0.40005 0 180)
			(size 0 0)
			(layers "F.Cu" "F.Mask" "F.Paste")
			(net "P12V_SCM_GATE")
		)
	)
	(footprint ""
		(layer "F.Cu")
		(at 131.64058 -27.52598 90)
		(property "Reference" "R6191"
			(at 0 0 90)
			(layer "F.SilkS")
			(hide yes)
			(effects
				(font
					(size 1.27 1.27)
				)
			)
		)
		(property "Value" ""
			(at 0 0 90)
			(layer "F.Fab")
			(effects
				(font
					(size 1.27 1.27)
				)
			)
		)
		(duplicate_pad_numbers_are_jumpers no)
		(fp_line
			(start 0.32512 -0.175006)
			(end 0.32512 0.175006)
			(stroke
				(width 0.1)
				(type default)
			)
			(layer "F.Fab")
		)
		(fp_line
			(start -0.32512 -0.175006)
			(end 0.32512 -0.175006)
			(stroke
				(width 0.1)
				(type default)
			)
			(layer "F.Fab")
		)
		(fp_line
			(start 0.32512 0.175006)
			(end -0.32512 0.175006)
			(stroke
				(width 0.1)
				(type default)
			)
			(layer "F.Fab")
		)
		(fp_line
			(start -0.32512 0.175006)
			(end -0.32512 -0.175006)
			(stroke
				(width 0.1)
				(type default)
			)
			(layer "F.Fab")
		)
		(pad "1" smd rect
			(at -0.2667 0 90)
			(size 0.3048 0.381)
			(layers "F.Cu" "F.Mask" "F.Paste")
			(net "USB2_CPU0_P0_DN")
		)
		(pad "2" smd rect
			(at 0.2667 0 270)
			(size 0.3048 0.381)
			(layers "F.Cu" "F.Mask" "F.Paste")
			(net "USB2_CPU0_P0_R1_DN")
		)
	)
	(footprint ""
		(layer "F.Cu")
		(at 265.006074 -140.624814 180)
		(property "Reference" "R8006"
			(at 0 0 180)
			(layer "F.SilkS")
			(hide yes)
			(effects
				(font
					(size 1.27 1.27)
				)
			)
		)
		(property "Value" ""
			(at 0 0 180)
			(layer "F.Fab")
			(effects
				(font
					(size 1.27 1.27)
				)
			)
		)
		(duplicate_pad_numbers_are_jumpers no)
		(fp_line
			(start 0.7874 0.4064)
			(end -0.7874 0.4064)
			(stroke
				(width 0.1524)
				(type default)
			)
			(layer "F.SilkS")
		)
		(fp_line
			(start 0.7874 -0.4064)
			(end 0.7874 0.4064)
			(stroke
				(width 0.1524)
				(type default)
			)
			(layer "F.SilkS")
		)
		(fp_line
			(start -0.7874 0.4064)
			(end -0.7874 -0.4064)
			(stroke
				(width 0.1524)
				(type default)
			)
			(layer "F.SilkS")
		)
		(fp_line
			(start -0.7874 -0.4064)
			(end 0.7874 -0.4064)
			(stroke
				(width 0.1524)
				(type default)
			)
			(layer "F.SilkS")
		)
		(fp_line
			(start 0.67945 0.3048)
			(end 0.120396 0.3048)
			(stroke
				(width 0.1)
				(type default)
			)
			(layer "F.Fab")
		)
		(fp_line
			(start 0.67945 -0.3048)
			(end 0.67945 0.3048)
			(stroke
				(width 0.1)
				(type default)
			)
			(layer "F.Fab")
		)
		(fp_line
			(start 0.12065 -0.2794)
			(end 0.12065 -0.3048)
			(stroke
				(width 0.1)
				(type default)
			)
			(layer "F.Fab")
		)
		(fp_line
			(start 0.12065 -0.3048)
			(end 0.67945 -0.3048)
			(stroke
				(width 0.1)
				(type default)
			)
			(layer "F.Fab")
		)
		(fp_line
			(start 0.120396 0.3048)
			(end 0.120396 0.2794)
			(stroke
				(width 0.1)
				(type default)
			)
			(layer "F.Fab")
		)
		(fp_line
			(start 0.120396 0.2794)
			(end -0.12065 0.2794)
			(stroke
				(width 0.1)
				(type default)
			)
			(layer "F.Fab")
		)
		(fp_line
			(start -0.12065 0.3048)
			(end -0.67945 0.3048)
			(stroke
				(width 0.1)
				(type default)
			)
			(layer "F.Fab")
		)
		(fp_line
			(start -0.12065 0.2794)
			(end -0.12065 0.3048)
			(stroke
				(width 0.1)
				(type default)
			)
			(layer "F.Fab")
		)
		(fp_line
			(start -0.12065 -0.2794)
			(end 0.12065 -0.2794)
			(stroke
				(width 0.1)
				(type default)
			)
			(layer "F.Fab")
		)
		(fp_line
			(start -0.12065 -0.305054)
			(end -0.12065 -0.2794)
			(stroke
				(width 0.1)
				(type default)
			)
			(layer "F.Fab")
		)
		(fp_line
			(start -0.67945 0.3048)
			(end -0.67945 -0.305054)
			(stroke
				(width 0.1)
				(type default)
			)
			(layer "F.Fab")
		)
		(fp_line
			(start -0.67945 -0.305054)
			(end -0.12065 -0.305054)
			(stroke
				(width 0.1)
				(type default)
			)
			(layer "F.Fab")
		)
		(pad "1" smd circle
			(at -0.40005 0 180)
			(size 0 0)
			(layers "F.Cu" "F.Mask" "F.Paste")
			(net "SPI_CPU0_D2")
		)
		(pad "2" smd circle
			(at 0.40005 0 180)
			(size 0 0)
			(layers "F.Cu" "F.Mask" "F.Paste")
			(net "SPI_CPU0_R1_D2")
		)
	)
)
